(kicad_pcb
	(version 20260206)
	(generator "pcbnew")
	(generator_version "10.0")
	(general
		(thickness 1.6)
		(legacy_teardrops no)
	)
	(paper "A4")
	(title_block
		(title "peb — Lightning_PEB_BRD.brd")
		(comment 1 "Lightning (Wiwynn / Facebook NVMe JBOF) / footprints 1594-1603 of 2563")
	)
	(layers
		(0 "F.Cu" signal "TOP")
		(4 "In1.Cu" signal "L2GND")
		(6 "In2.Cu" signal "L3")
		(8 "In3.Cu" signal "L4VCC")
		(10 "In4.Cu" signal "L5VCC")
		(12 "In5.Cu" signal "L6")
		(14 "In6.Cu" signal "L7GND")
		(2 "B.Cu" signal "BOTTOM")
		(9 "F.Adhes" user "F.Adhesive")
		(11 "B.Adhes" user "B.Adhesive")
		(13 "F.Paste" user "Package Geometry/Pastemask Top")
		(15 "B.Paste" user "Package Geometry/Pastemask Bottom")
		(5 "F.SilkS" user "Ref Des/Silkscreen Top")
		(7 "B.SilkS" user "Ref Des/Silkscreen Bottom")
		(1 "F.Mask" user "Board Geometry/Soldermask Top")
		(3 "B.Mask" user "Board Geometry/Soldermask Bottom")
		(17 "Dwgs.User" user "User.Drawings")
		(19 "Cmts.User" user "User.Comments")
		(21 "Eco1.User" user "User.Eco1")
		(23 "Eco2.User" user "User.Eco2")
		(25 "Edge.Cuts" user "Board Geometry/Outline")
		(27 "Margin" user)
		(31 "F.CrtYd" user "Package Geometry/Place Bound Top")
		(29 "B.CrtYd" user "Package Geometry/Place Bound Bottom")
		(35 "F.Fab" user "Ref Des/Assembly Top")
		(33 "B.Fab" user "Ref Des/Assembly Bottom")
	)
	(footprint ""
		(layer "F.Cu")
		(at 108.608114 -212.420454 180)
		(property "Reference" "C144"
			(at 0 0 180)
			(layer "F.SilkS")
			(hide yes)
			(effects
				(font
					(size 1.27 1.27)
				)
			)
		)
		(property "Value" "SCD22U10V2KX-1GP"
			(at 1.1811 -2.7051 180)
			(unlocked yes)
			(layer "F.Fab")
			(hide yes)
			(effects
				(font
					(size 1.016 1.016)
					(thickness 0.1524)
				)
			)
		)
		(property "Device Type" "C402H22"
			(at 1.1811 -4.2291 180)
			(unlocked yes)
			(layer "F.Fab")
			(hide yes)
			(effects
				(font
					(size 1.016 1.016)
					(thickness 0.1524)
				)
			)
		)
		(duplicate_pad_numbers_are_jumpers no)
		(fp_rect
			(start -0.4318 0.9525)
			(end 0.4318 -0.9525)
			(stroke
				(width 0)
				(type default)
			)
			(fill no)
			(layer "F.CrtYd")
		)
		(fp_rect
			(start -0.4318 0.9525)
			(end 0.4318 -0.9525)
			(stroke
				(width 0)
				(type default)
			)
			(fill no)
			(layer "F.Fab")
		)
		(pad "1" smd custom
			(at 0 -0.4445 180)
			(size 0.1524 0.1524)
			(layers "F.Cu" "F.Mask" "F.Paste")
			(net "PCIE_TX_CAP_N60")
			(options
				(clearance outline)
				(anchor circle)
			)
			(primitives
				(gr_poly
					(pts
						(arc
							(start 0.3048 -0.2032)
							(mid 0.275042 -0.275042)
							(end 0.2032 -0.3048)
						)
						(arc
							(start -0.2032 -0.3048)
							(mid -0.275042 -0.275042)
							(end -0.3048 -0.2032)
						)
						(arc
							(start -0.3048 0.2032)
							(mid -0.275042 0.275042)
							(end -0.2032 0.3048)
						)
						(arc
							(start 0.2032 0.3048)
							(mid 0.275042 0.275042)
							(end 0.3048 0.2032)
						)
					)
					(width 0)
					(fill yes)
				)
			)
		)
		(pad "2" smd custom
			(at 0 0.4445 180)
			(size 0.1524 0.1524)
			(layers "F.Cu" "F.Mask" "F.Paste")
			(net "PCIE_TX_N60")
			(options
				(clearance outline)
				(anchor circle)
			)
			(primitives
				(gr_poly
					(pts
						(arc
							(start 0.3048 -0.2032)
							(mid 0.275042 -0.275042)
							(end 0.2032 -0.3048)
						)
						(arc
							(start -0.2032 -0.3048)
							(mid -0.275042 -0.275042)
							(end -0.3048 -0.2032)
						)
						(arc
							(start -0.3048 0.2032)
							(mid -0.275042 0.275042)
							(end -0.2032 0.3048)
						)
						(arc
							(start 0.2032 0.3048)
							(mid 0.275042 0.275042)
							(end 0.3048 0.2032)
						)
					)
					(width 0)
					(fill yes)
				)
			)
		)
	)
	(footprint ""
		(layer "F.Cu")
		(at 30.607 -117.094)
		(property "Reference" "TP242"
			(at 0 0 0)
			(layer "F.SilkS")
			(hide yes)
			(effects
				(font
					(size 1.27 1.27)
				)
			)
		)
		(property "Value" "TPAD28-2-GP"
			(at -0.0127 -1.6637 0)
			(unlocked yes)
			(layer "F.Fab")
			(hide yes)
			(effects
				(font
					(size 1.016 1.016)
					(thickness 0.1524)
				)
			)
		)
		(property "Device Type" "TPAD28"
			(at -0.0127 -3.1877 0)
			(unlocked yes)
			(layer "F.Fab")
			(hide yes)
			(effects
				(font
					(size 1.016 1.016)
					(thickness 0.1524)
				)
			)
		)
		(duplicate_pad_numbers_are_jumpers no)
		(fp_poly
			(pts
				(arc
					(start 0.3556 0)
					(mid -0.3556 0)
					(end 0.3556 0)
				)
			)
			(stroke
				(width 0)
				(type default)
			)
			(fill no)
			(layer "F.CrtYd")
		)
		(fp_poly
			(pts
				(arc
					(start 0.6096 0)
					(mid -0.6096 0)
					(end 0.6096 0)
				)
			)
			(stroke
				(width 0)
				(type default)
			)
			(fill no)
			(layer "F.Fab")
		)
		(pad "1" smd circle
			(at 0 0)
			(size 0.7112 0.7112)
			(layers "F.Cu" "F.Mask" "F.Paste")
			(net "TP_GPIOD2")
		)
	)
	(footprint ""
		(layer "F.Cu")
		(at 131.0513 -33.54324)
		(property "Reference" "C383"
			(at 0 0 0)
			(layer "F.SilkS")
			(hide yes)
			(effects
				(font
					(size 1.27 1.27)
				)
			)
		)
		(property "Value" "SCD22U10V2KX-1GP"
			(at 1.1811 -2.7051 0)
			(unlocked yes)
			(layer "F.Fab")
			(hide yes)
			(effects
				(font
					(size 1.016 1.016)
					(thickness 0.1524)
				)
			)
		)
		(property "Device Type" "C402H22"
			(at 1.1811 -4.2291 0)
			(unlocked yes)
			(layer "F.Fab")
			(hide yes)
			(effects
				(font
					(size 1.016 1.016)
					(thickness 0.1524)
				)
			)
		)
		(duplicate_pad_numbers_are_jumpers no)
		(fp_rect
			(start -0.4318 0.9525)
			(end 0.4318 -0.9525)
			(stroke
				(width 0)
				(type default)
			)
			(fill no)
			(layer "F.CrtYd")
		)
		(fp_rect
			(start -0.4318 0.9525)
			(end 0.4318 -0.9525)
			(stroke
				(width 0)
				(type default)
			)
			(fill no)
			(layer "F.Fab")
		)
		(pad "1" smd custom
			(at 0 -0.4445)
			(size 0.1524 0.1524)
			(layers "F.Cu" "F.Mask" "F.Paste")
			(net "PCIE_TX_CAP_P81")
			(options
				(clearance outline)
				(anchor circle)
			)
			(primitives
				(gr_poly
					(pts
						(arc
							(start 0.3048 -0.2032)
							(mid 0.275042 -0.275042)
							(end 0.2032 -0.3048)
						)
						(arc
							(start -0.2032 -0.3048)
							(mid -0.275042 -0.275042)
							(end -0.3048 -0.2032)
						)
						(arc
							(start -0.3048 0.2032)
							(mid -0.275042 0.275042)
							(end -0.2032 0.3048)
						)
						(arc
							(start 0.2032 0.3048)
							(mid 0.275042 0.275042)
							(end 0.3048 0.2032)
						)
					)
					(width 0)
					(fill yes)
				)
			)
		)
		(pad "2" smd custom
			(at 0 0.4445)
			(size 0.1524 0.1524)
			(layers "F.Cu" "F.Mask" "F.Paste")
			(net "PCIE_TX_P81")
			(options
				(clearance outline)
				(anchor circle)
			)
			(primitives
				(gr_poly
					(pts
						(arc
							(start 0.3048 -0.2032)
							(mid 0.275042 -0.275042)
							(end 0.2032 -0.3048)
						)
						(arc
							(start -0.2032 -0.3048)
							(mid -0.275042 -0.275042)
							(end -0.3048 -0.2032)
						)
						(arc
							(start -0.3048 0.2032)
							(mid -0.275042 0.275042)
							(end -0.2032 0.3048)
						)
						(arc
							(start 0.2032 0.3048)
							(mid 0.275042 0.275042)
							(end 0.3048 0.2032)
						)
					)
					(width 0)
					(fill yes)
				)
			)
		)
	)
	(footprint ""
		(layer "F.Cu")
		(at 18.288 -154.432)
		(property "Reference" "R8003"
			(at 0 0 0)
			(layer "F.SilkS")
			(hide yes)
			(effects
				(font
					(size 1.27 1.27)
				)
			)
		)
		(property "Value" "0R2J-2-GP"
			(at 0.064008 -3.993896 0)
			(unlocked yes)
			(layer "F.Fab")
			(hide yes)
			(effects
				(font
					(size 1.016 1.016)
					(thickness 0.1524)
				)
			)
		)
		(property "Device Type" "R402H16"
			(at 0.064008 -5.517896 0)
			(unlocked yes)
			(layer "F.Fab")
			(hide yes)
			(effects
				(font
					(size 1.016 1.016)
					(thickness 0.1524)
				)
			)
		)
		(duplicate_pad_numbers_are_jumpers no)
		(fp_line
			(start -0.508 -0.9398)
			(end -0.508 0.9398)
			(stroke
				(width 0.1524)
				(type default)
			)
			(layer "F.SilkS")
		)
		(fp_line
			(start 0.508 -0.9398)
			(end -0.508 -0.9398)
			(stroke
				(width 0.1524)
				(type default)
			)
			(layer "F.SilkS")
		)
		(fp_rect
			(start -0.508 0.9398)
			(end 0.508 -0.9398)
			(stroke
				(width 0)
				(type default)
			)
			(fill no)
			(layer "F.CrtYd")
		)
		(fp_rect
			(start -0.508 0.9398)
			(end 0.508 -0.9398)
			(stroke
				(width 0)
				(type default)
			)
			(fill no)
			(layer "F.Fab")
		)
		(pad "1" smd custom
			(at 0 -0.4445)
			(size 0.1397 0.1397)
			(layers "F.Cu" "F.Mask" "F.Paste")
			(net "FM_BMC_RESET#_BTN_D")
			(options
				(clearance outline)
				(anchor circle)
			)
			(primitives
				(gr_poly
					(pts
						(arc
							(start -0.1778 -0.2794)
							(mid -0.249642 -0.249642)
							(end -0.2794 -0.1778)
						)
						(arc
							(start -0.2794 0.1778)
							(mid -0.249642 0.249642)
							(end -0.1778 0.2794)
						)
						(arc
							(start 0.1778 0.2794)
							(mid 0.249642 0.249642)
							(end 0.2794 0.1778)
						)
						(arc
							(start 0.2794 -0.1778)
							(mid 0.249642 -0.249642)
							(end 0.1778 -0.2794)
						)
					)
					(width 0)
					(fill yes)
				)
			)
		)
		(pad "2" smd custom
			(at 0 0.4445)
			(size 0.1397 0.1397)
			(layers "F.Cu" "F.Mask" "F.Paste")
			(net "FM_BMC_RESET_Q36")
			(options
				(clearance outline)
				(anchor circle)
			)
			(primitives
				(gr_poly
					(pts
						(arc
							(start -0.1778 -0.2794)
							(mid -0.249642 -0.249642)
							(end -0.2794 -0.1778)
						)
						(arc
							(start -0.2794 0.1778)
							(mid -0.249642 0.249642)
							(end -0.1778 0.2794)
						)
						(arc
							(start 0.1778 0.2794)
							(mid 0.249642 0.249642)
							(end 0.2794 0.1778)
						)
						(arc
							(start 0.2794 -0.1778)
							(mid 0.249642 -0.249642)
							(end 0.1778 -0.2794)
						)
					)
					(width 0)
					(fill yes)
				)
			)
		)
	)
	(footprint ""
		(layer "F.Cu")
		(at 346.456 -58.547 90)
		(property "Reference" "PC220"
			(at 0 0 90)
			(layer "F.SilkS")
			(hide yes)
			(effects
				(font
					(size 1.27 1.27)
				)
			)
		)
		(property "Value" "SC22U25V6KX-GP-U"
			(at -2.860802 -5.279644 90)
			(unlocked yes)
			(layer "F.Fab")
			(hide yes)
			(effects
				(font
					(size 1.016 1.016)
					(thickness 0.1524)
				)
			)
		)
		(property "Device Type" "C1206-TO0D3H75"
			(at -2.860802 -6.803644 90)
			(unlocked yes)
			(layer "F.Fab")
			(hide yes)
			(effects
				(font
					(size 1.016 1.016)
					(thickness 0.1524)
				)
			)
		)
		(duplicate_pad_numbers_are_jumpers no)
		(fp_line
			(start 1.3081 -2.3749)
			(end 1.3081 2.3749)
			(stroke
				(width 0.1524)
				(type default)
			)
			(layer "F.SilkS")
		)
		(fp_line
			(start -1.3081 -2.3749)
			(end 1.3081 -2.3749)
			(stroke
				(width 0.1524)
				(type default)
			)
			(layer "F.SilkS")
		)
		(fp_line
			(start 1.3081 2.3749)
			(end -1.3081 2.3749)
			(stroke
				(width 0.1524)
				(type default)
			)
			(layer "F.SilkS")
		)
		(fp_line
			(start -1.3081 2.3749)
			(end -1.3081 -2.3749)
			(stroke
				(width 0.1524)
				(type default)
			)
			(layer "F.SilkS")
		)
		(fp_rect
			(start -0.8001 1.6002)
			(end 0.8001 -1.6002)
			(stroke
				(width 0)
				(type default)
			)
			(fill no)
			(layer "F.CrtYd")
		)
		(fp_poly
			(pts
				(xy -1.5621 2.4511) (xy -1.5621 1.6002) (xy 0.8001 1.6002) (xy 0.8001 -1.6002) (xy -0.8001 -1.6002)
				(xy -0.8001 1.5875) (xy -1.5621 1.5875) (xy -1.5621 -2.4511) (xy 1.5621 -2.4511) (xy 1.5621 2.4511)
			)
			(stroke
				(width 0)
				(type default)
			)
			(fill no)
			(layer "F.CrtYd")
		)
		(fp_rect
			(start -1.5621 2.4511)
			(end 1.5621 -2.4511)
			(stroke
				(width 0)
				(type default)
			)
			(fill no)
			(layer "F.Fab")
		)
		(pad "1" smd rect
			(at 0 -1.392936 90)
			(size 2.1082 1.4478)
			(layers "F.Cu" "F.Mask" "F.Paste")
			(net "P0V9_E_VIN")
		)
		(pad "2" smd rect
			(at 0 1.392936 90)
			(size 2.1082 1.4478)
			(layers "F.Cu" "F.Mask" "F.Paste")
			(net "GND")
		)
	)
	(footprint ""
		(layer "F.Cu")
		(at 294.108378 -33.694116)
		(property "Reference" "C12"
			(at 0 0 0)
			(layer "F.SilkS")
			(hide yes)
			(effects
				(font
					(size 1.27 1.27)
				)
			)
		)
		(property "Value" "SCD22U10V2KX-1GP"
			(at 1.1811 -2.7051 0)
			(unlocked yes)
			(layer "F.Fab")
			(hide yes)
			(effects
				(font
					(size 1.016 1.016)
					(thickness 0.1524)
				)
			)
		)
		(property "Device Type" "C402H22"
			(at 1.1811 -4.2291 0)
			(unlocked yes)
			(layer "F.Fab")
			(hide yes)
			(effects
				(font
					(size 1.016 1.016)
					(thickness 0.1524)
				)
			)
		)
		(duplicate_pad_numbers_are_jumpers no)
		(fp_rect
			(start -0.4318 0.9525)
			(end 0.4318 -0.9525)
			(stroke
				(width 0)
				(type default)
			)
			(fill no)
			(layer "F.CrtYd")
		)
		(fp_rect
			(start -0.4318 0.9525)
			(end 0.4318 -0.9525)
			(stroke
				(width 0)
				(type default)
			)
			(fill no)
			(layer "F.Fab")
		)
		(pad "1" smd custom
			(at 0 -0.4445)
			(size 0.1524 0.1524)
			(layers "F.Cu" "F.Mask" "F.Paste")
			(net "PCIE_TX_CAP_P4")
			(options
				(clearance outline)
				(anchor circle)
			)
			(primitives
				(gr_poly
					(pts
						(arc
							(start 0.3048 -0.2032)
							(mid 0.275042 -0.275042)
							(end 0.2032 -0.3048)
						)
						(arc
							(start -0.2032 -0.3048)
							(mid -0.275042 -0.275042)
							(end -0.3048 -0.2032)
						)
						(arc
							(start -0.3048 0.2032)
							(mid -0.275042 0.275042)
							(end -0.2032 0.3048)
						)
						(arc
							(start 0.2032 0.3048)
							(mid 0.275042 0.275042)
							(end 0.3048 0.2032)
						)
					)
					(width 0)
					(fill yes)
				)
			)
		)
		(pad "2" smd custom
			(at 0 0.4445)
			(size 0.1524 0.1524)
			(layers "F.Cu" "F.Mask" "F.Paste")
			(net "PCIE_TX_P4")
			(options
				(clearance outline)
				(anchor circle)
			)
			(primitives
				(gr_poly
					(pts
						(arc
							(start 0.3048 -0.2032)
							(mid 0.275042 -0.275042)
							(end 0.2032 -0.3048)
						)
						(arc
							(start -0.2032 -0.3048)
							(mid -0.275042 -0.275042)
							(end -0.3048 -0.2032)
						)
						(arc
							(start -0.3048 0.2032)
							(mid -0.275042 0.275042)
							(end -0.2032 0.3048)
						)
						(arc
							(start 0.2032 0.3048)
							(mid 0.275042 0.275042)
							(end 0.3048 0.2032)
						)
					)
					(width 0)
					(fill yes)
				)
			)
		)
	)
	(footprint ""
		(layer "F.Cu")
		(at 25.916128 -120.719596 -90)
		(property "Reference" "TP266"
			(at 0 0 270)
			(layer "F.SilkS")
			(hide yes)
			(effects
				(font
					(size 1.27 1.27)
				)
			)
		)
		(property "Value" "TPAD28-2-GP"
			(at -0.0127 -1.6637 270)
			(unlocked yes)
			(layer "F.Fab")
			(hide yes)
			(effects
				(font
					(size 1.016 1.016)
					(thickness 0.1524)
				)
			)
		)
		(property "Device Type" "TPAD28"
			(at -0.0127 -3.1877 270)
			(unlocked yes)
			(layer "F.Fab")
			(hide yes)
			(effects
				(font
					(size 1.016 1.016)
					(thickness 0.1524)
				)
			)
		)
		(duplicate_pad_numbers_are_jumpers no)
		(fp_poly
			(pts
				(arc
					(start 0 -0.3556)
					(mid 0 0.3556)
					(end 0 -0.3556)
				)
			)
			(stroke
				(width 0)
				(type default)
			)
			(fill no)
			(layer "F.CrtYd")
		)
		(fp_poly
			(pts
				(arc
					(start 0 -0.6096)
					(mid 0 0.6096)
					(end 0 -0.6096)
				)
			)
			(stroke
				(width 0)
				(type default)
			)
			(fill no)
			(layer "F.Fab")
		)
		(pad "1" smd circle
			(at 0 0 270)
			(size 0.7112 0.7112)
			(layers "F.Cu" "F.Mask" "F.Paste")
			(net "TP_GPIOI0")
		)
	)
	(footprint ""
		(layer "F.Cu")
		(at 104.392222 -212.420454 180)
		(property "Reference" "C149"
			(at 0 0 180)
			(layer "F.SilkS")
			(hide yes)
			(effects
				(font
					(size 1.27 1.27)
				)
			)
		)
		(property "Value" "SCD22U10V2KX-1GP"
			(at 1.1811 -2.7051 180)
			(unlocked yes)
			(layer "F.Fab")
			(hide yes)
			(effects
				(font
					(size 1.016 1.016)
					(thickness 0.1524)
				)
			)
		)
		(property "Device Type" "C402H22"
			(at 1.1811 -4.2291 180)
			(unlocked yes)
			(layer "F.Fab")
			(hide yes)
			(effects
				(font
					(size 1.016 1.016)
					(thickness 0.1524)
				)
			)
		)
		(duplicate_pad_numbers_are_jumpers no)
		(fp_rect
			(start -0.4318 0.9525)
			(end 0.4318 -0.9525)
			(stroke
				(width 0)
				(type default)
			)
			(fill no)
			(layer "F.CrtYd")
		)
		(fp_rect
			(start -0.4318 0.9525)
			(end 0.4318 -0.9525)
			(stroke
				(width 0)
				(type default)
			)
			(fill no)
			(layer "F.Fab")
		)
		(pad "1" smd custom
			(at 0 -0.4445 180)
			(size 0.1524 0.1524)
			(layers "F.Cu" "F.Mask" "F.Paste")
			(net "PCIE_TX_CAP_P61")
			(options
				(clearance outline)
				(anchor circle)
			)
			(primitives
				(gr_poly
					(pts
						(arc
							(start 0.3048 -0.2032)
							(mid 0.275042 -0.275042)
							(end 0.2032 -0.3048)
						)
						(arc
							(start -0.2032 -0.3048)
							(mid -0.275042 -0.275042)
							(end -0.3048 -0.2032)
						)
						(arc
							(start -0.3048 0.2032)
							(mid -0.275042 0.275042)
							(end -0.2032 0.3048)
						)
						(arc
							(start 0.2032 0.3048)
							(mid 0.275042 0.275042)
							(end 0.3048 0.2032)
						)
					)
					(width 0)
					(fill yes)
				)
			)
		)
		(pad "2" smd custom
			(at 0 0.4445 180)
			(size 0.1524 0.1524)
			(layers "F.Cu" "F.Mask" "F.Paste")
			(net "PCIE_TX_P61")
			(options
				(clearance outline)
				(anchor circle)
			)
			(primitives
				(gr_poly
					(pts
						(arc
							(start 0.3048 -0.2032)
							(mid 0.275042 -0.275042)
							(end 0.2032 -0.3048)
						)
						(arc
							(start -0.2032 -0.3048)
							(mid -0.275042 -0.275042)
							(end -0.3048 -0.2032)
						)
						(arc
							(start -0.3048 0.2032)
							(mid -0.275042 0.275042)
							(end -0.2032 0.3048)
						)
						(arc
							(start 0.2032 0.3048)
							(mid 0.275042 0.275042)
							(end 0.3048 0.2032)
						)
					)
					(width 0)
					(fill yes)
				)
			)
		)
	)
	(footprint ""
		(layer "F.Cu")
		(at 298.958 -57.0992)
		(property "Reference" "C425"
			(at 0 0 0)
			(layer "F.SilkS")
			(hide yes)
			(effects
				(font
					(size 1.27 1.27)
				)
			)
		)
		(property "Value" "SC10U16V5KX-1-GP"
			(at -0.0762 -6.1214 0)
			(unlocked yes)
			(layer "F.Fab")
			(hide yes)
			(effects
				(font
					(size 1.016 1.016)
					(thickness 0.1524)
				)
			)
		)
		(property "Device Type" "C805H54"
			(at -0.0762 -8.1534 0)
			(unlocked yes)
			(layer "F.Fab")
			(hide yes)
			(effects
				(font
					(size 1.016 1.016)
					(thickness 0.1524)
				)
			)
		)
		(duplicate_pad_numbers_are_jumpers no)
		(fp_line
			(start 0.635 0)
			(end -0.635 0)
			(stroke
				(width 0.508)
				(type default)
			)
			(layer "F.SilkS")
		)
		(fp_rect
			(start -0.9652 1.778)
			(end 0.9652 -1.778)
			(stroke
				(width 0)
				(type default)
			)
			(fill no)
			(layer "F.CrtYd")
		)
		(fp_poly
			(pts
				(xy -0.9652 -1.778) (xy 0.9652 -1.778) (xy 0.9652 1.778) (xy -0.9652 1.778)
			)
			(stroke
				(width 0)
				(type default)
			)
			(fill no)
			(layer "F.Fab")
		)
		(pad "1" smd rect
			(at 0 -0.9652)
			(size 1.397 1.143)
			(layers "F.Cu" "F.Mask" "F.Paste")
			(net "DUT_VDD")
		)
		(pad "2" smd rect
			(at 0 0.9652)
			(size 1.397 1.143)
			(layers "F.Cu" "F.Mask" "F.Paste")
			(net "GND")
		)
	)
	(footprint ""
		(layer "F.Cu")
		(at 8.001 -111.252 180)
		(property "Reference" "PC82"
			(at 0 0 180)
			(layer "F.SilkS")
			(hide yes)
			(effects
				(font
					(size 1.27 1.27)
				)
			)
		)
		(property "Value" "SC22U6D3V5MX-5-GP"
			(at -0.0762 -6.1214 180)
			(unlocked yes)
			(layer "F.Fab")
			(hide yes)
			(effects
				(font
					(size 1.016 1.016)
					(thickness 0.1524)
				)
			)
		)
		(property "Device Type" "C805H56"
			(at -0.0762 -8.1534 180)
			(unlocked yes)
			(layer "F.Fab")
			(hide yes)
			(effects
				(font
					(size 1.016 1.016)
					(thickness 0.1524)
				)
			)
		)
		(duplicate_pad_numbers_are_jumpers no)
		(fp_line
			(start 0.635 0)
			(end -0.635 0)
			(stroke
				(width 0.508)
				(type default)
			)
			(layer "F.SilkS")
		)
		(fp_rect
			(start -0.9652 1.778)
			(end 0.9652 -1.778)
			(stroke
				(width 0)
				(type default)
			)
			(fill no)
			(layer "F.CrtYd")
		)
		(fp_poly
			(pts
				(xy -0.9652 -1.778) (xy 0.9652 -1.778) (xy 0.9652 1.778) (xy -0.9652 1.778)
			)
			(stroke
				(width 0)
				(type default)
			)
			(fill no)
			(layer "F.Fab")
		)
		(pad "1" smd rect
			(at 0 -0.9652 180)
			(size 1.397 1.143)
			(layers "F.Cu" "F.Mask" "F.Paste")
			(net "VR_P1V26_STBY_IN")
		)
		(pad "2" smd rect
			(at 0 0.9652 180)
			(size 1.397 1.143)
			(layers "F.Cu" "F.Mask" "F.Paste")
			(net "GND")
		)
	)
)
